# BASEBOARD_FAB2 (Tioga Pass) — schematic netlist excerpt (pin names and nets, part order shuffled) for the footprints in the layout excerpt that follows; sources: Cadence DE-HDL packaged netlist, KiCad conversion of Wiwynn_Tioga_Pass_MB.brd

R6W6  RES  4.75K 1% CHIP  pkg 0402  page 247 : A = P3V3_STBY ; B = PCA9555_A0
R3P1  RES  0.0 5% CHIP  pkg 0402  page 211 : A = SVID_ALERT_PVCCIO_CPU0 ; B = SVID_ALERT0_CPU0_R_N
R9N7  RES  3.16K 1% CHIP  pkg 0402  page 206 : A = VR_PVCCIN_CPU1_XADDR2 ; B = GND

(kicad_pcb
	(version 20260206)
	(generator "pcbnew")
	(generator_version "10.0")
	(general
		(thickness 1.6)
		(legacy_teardrops no)
	)
	(paper "A4")
	(title_block
		(title "Wiwynn_Tioga_Pass_MB.brd")
		(comment 1 "Tioga Pass / footprints 2828-2830 of 4770")
	)
	(layers
		(0 "F.Cu" signal "TOP")
		(4 "In1.Cu" signal "L2GND")
		(6 "In2.Cu" signal "L3")
		(8 "In3.Cu" signal "L4GND")
		(10 "In4.Cu" signal "L5")
		(12 "In5.Cu" signal "L6GND")
		(14 "In6.Cu" signal "L7VCC")
		(16 "In7.Cu" signal "L8VCC")
		(18 "In8.Cu" signal "L9GND")
		(20 "In9.Cu" signal "L10")
		(22 "In10.Cu" signal "L11GND")
		(24 "In11.Cu" signal "L12")
		(26 "In12.Cu" signal "L13GND")
		(2 "B.Cu" signal "BOTTOM")
		(9 "F.Adhes" user "F.Adhesive")
		(11 "B.Adhes" user "B.Adhesive")
		(13 "F.Paste" user "Package Geometry/Pastemask Top")
		(15 "B.Paste" user "Package Geometry/Pastemask Bottom")
		(5 "F.SilkS" user "Ref Des/Silkscreen Top")
		(7 "B.SilkS" user "Ref Des/Silkscreen Bottom")
		(1 "F.Mask" user "Board Geometry/Soldermask Top")
		(3 "B.Mask" user "Board Geometry/Soldermask Bottom")
		(17 "Dwgs.User" user "User.Drawings")
		(19 "Cmts.User" user "User.Comments")
		(21 "Eco1.User" user "User.Eco1")
		(23 "Eco2.User" user "User.Eco2")
		(25 "Edge.Cuts" user "Board Geometry/Outline")
		(27 "Margin" user)
		(31 "F.CrtYd" user "Package Geometry/Place Bound Top")
		(29 "B.CrtYd" user "Package Geometry/Place Bound Bottom")
		(35 "F.Fab" user "Ref Des/Assembly Top")
		(33 "B.Fab" user "Ref Des/Assembly Bottom")
	)
	(footprint ""
		(layer "B.Cu")
		(at 476.174816 -146.359372)
		(property "Reference" "R6W6"
			(at 0.8382 -0.67818 0)
			(unlocked yes)
			(layer "B.SilkS")
			(effects
				(font
					(size 0.4064 0.254)
					(thickness 0.1524)
				)
				(justify left mirror)
			)
		)
		(property "Value" ""
			(at 0 0 0)
			(layer "B.Fab")
			(effects
				(font
					(size 1.27 1.27)
				)
				(justify mirror)
			)
		)
		(duplicate_pad_numbers_are_jumpers no)
		(fp_poly
			(pts
				(xy 0.2794 -0.1016) (xy -0.2794 -0.1016) (xy -0.2794 0.9906) (xy 0.2794 0.9906)
			)
			(stroke
				(width 0)
				(type default)
			)
			(fill no)
			(layer "B.CrtYd")
		)
		(fp_line
			(start -0.2794 -0.1016)
			(end 0.2794 -0.1016)
			(stroke
				(width 0.1)
				(type default)
			)
			(layer "B.Fab")
		)
		(fp_line
			(start -0.2794 0.9906)
			(end -0.2794 -0.1016)
			(stroke
				(width 0.1)
				(type default)
			)
			(layer "B.Fab")
		)
		(fp_line
			(start 0.2794 -0.1016)
			(end 0.2794 0.9906)
			(stroke
				(width 0.1)
				(type default)
			)
			(layer "B.Fab")
		)
		(fp_line
			(start 0.2794 0.9906)
			(end -0.2794 0.9906)
			(stroke
				(width 0.1)
				(type default)
			)
			(layer "B.Fab")
		)
		(pad "1" smd rect
			(at 0 0 180)
			(size 0.508 0.508)
			(layers "B.Cu" "B.Mask" "B.Paste")
			(net "P3V3_STBY")
		)
		(pad "2" smd rect
			(at 0 0.889 180)
			(size 0.508 0.508)
			(layers "B.Cu" "B.Mask" "B.Paste")
			(net "PCA9555_A0")
		)
		(zone
			(layer "B.Cu")
			(hatch none 0.5)
			(connect_pads
				(clearance 0)
			)
			(min_thickness 0.25)
			(keepout
				(tracks allowed)
				(vias not_allowed)
				(pads allowed)
				(copperpour not_allowed)
				(footprints allowed)
			)
			(placement
				(enabled no)
				(sheetname "")
			)
			(fill
				(thermal_gap 0.5)
				(thermal_bridge_width 0.5)
				(island_removal_mode 0)
			)
			(polygon
				(pts
					(xy 476.428816 -146.105372) (xy 475.920816 -146.105372) (xy 475.920816 -145.724372) (xy 476.428816 -145.724372)
				)
			)
		)
		(zone
			(layer "B.Cu")
			(hatch none 0.5)
			(connect_pads
				(clearance 0)
			)
			(min_thickness 0.25)
			(keepout
				(tracks not_allowed)
				(vias allowed)
				(pads allowed)
				(copperpour not_allowed)
				(footprints allowed)
			)
			(placement
				(enabled no)
				(sheetname "")
			)
			(fill
				(thermal_gap 0.5)
				(thermal_bridge_width 0.5)
				(island_removal_mode 0)
			)
			(polygon
				(pts
					(xy 476.428816 -145.724372) (xy 475.920816 -145.724372) (xy 475.920816 -146.105372) (xy 476.428816 -146.105372)
				)
			)
		)
	)
	(footprint ""
		(layer "B.Cu")
		(at 20.193 -95.5294)
		(property "Reference" "R9N7"
			(at 0 0 0)
			(layer "B.SilkS")
			(hide yes)
			(effects
				(font
					(size 1.27 1.27)
				)
				(justify mirror)
			)
		)
		(property "Value" ""
			(at 0 0 0)
			(layer "B.Fab")
			(effects
				(font
					(size 1.27 1.27)
				)
				(justify mirror)
			)
		)
		(duplicate_pad_numbers_are_jumpers no)
		(fp_poly
			(pts
				(xy 0.2794 -0.1016) (xy -0.2794 -0.1016) (xy -0.2794 0.9906) (xy 0.2794 0.9906)
			)
			(stroke
				(width 0)
				(type default)
			)
			(fill no)
			(layer "B.CrtYd")
		)
		(fp_line
			(start -0.2794 -0.1016)
			(end 0.2794 -0.1016)
			(stroke
				(width 0.1)
				(type default)
			)
			(layer "B.Fab")
		)
		(fp_line
			(start -0.2794 0.9906)
			(end -0.2794 -0.1016)
			(stroke
				(width 0.1)
				(type default)
			)
			(layer "B.Fab")
		)
		(fp_line
			(start 0.2794 -0.1016)
			(end 0.2794 0.9906)
			(stroke
				(width 0.1)
				(type default)
			)
			(layer "B.Fab")
		)
		(fp_line
			(start 0.2794 0.9906)
			(end -0.2794 0.9906)
			(stroke
				(width 0.1)
				(type default)
			)
			(layer "B.Fab")
		)
		(pad "1" smd rect
			(at 0 0 180)
			(size 0.508 0.508)
			(layers "B.Cu" "B.Mask" "B.Paste")
			(net "VR_PVCCIN_CPU1_XADDR2")
		)
		(pad "2" smd rect
			(at 0 0.889 180)
			(size 0.508 0.508)
			(layers "B.Cu" "B.Mask" "B.Paste")
			(net "GND")
		)
		(zone
			(layer "B.Cu")
			(hatch none 0.5)
			(connect_pads
				(clearance 0)
			)
			(min_thickness 0.25)
			(keepout
				(tracks allowed)
				(vias not_allowed)
				(pads allowed)
				(copperpour not_allowed)
				(footprints allowed)
			)
			(placement
				(enabled no)
				(sheetname "")
			)
			(fill
				(thermal_gap 0.5)
				(thermal_bridge_width 0.5)
				(island_removal_mode 0)
			)
			(polygon
				(pts
					(xy 20.447 -95.2754) (xy 19.939 -95.2754) (xy 19.939 -94.8944) (xy 20.447 -94.8944)
				)
			)
		)
		(zone
			(layer "B.Cu")
			(hatch none 0.5)
			(connect_pads
				(clearance 0)
			)
			(min_thickness 0.25)
			(keepout
				(tracks not_allowed)
				(vias allowed)
				(pads allowed)
				(copperpour not_allowed)
				(footprints allowed)
			)
			(placement
				(enabled no)
				(sheetname "")
			)
			(fill
				(thermal_gap 0.5)
				(thermal_bridge_width 0.5)
				(island_removal_mode 0)
			)
			(polygon
				(pts
					(xy 20.447 -94.8944) (xy 19.939 -94.8944) (xy 19.939 -95.2754) (xy 20.447 -95.2754)
				)
			)
		)
	)
	(footprint ""
		(layer "B.Cu")
		(at 342.0872 -88.3412 -90)
		(property "Reference" "R3P1"
			(at 0 0 90)
			(layer "B.SilkS")
			(hide yes)
			(effects
				(font
					(size 1.27 1.27)
				)
				(justify mirror)
			)
		)
		(property "Value" ""
			(at 0 0 90)
			(layer "B.Fab")
			(effects
				(font
					(size 1.27 1.27)
				)
				(justify mirror)
			)
		)
		(duplicate_pad_numbers_are_jumpers no)
		(fp_poly
			(pts
				(xy 0.2794 -0.1016) (xy -0.2794 -0.1016) (xy -0.2794 0.9906) (xy 0.2794 0.9906)
			)
			(stroke
				(width 0)
				(type default)
			)
			(fill no)
			(layer "B.CrtYd")
		)
		(fp_line
			(start -0.2794 0.9906)
			(end -0.2794 -0.1016)
			(stroke
				(width 0.1)
				(type default)
			)
			(layer "B.Fab")
		)
		(fp_line
			(start 0.2794 0.9906)
			(end -0.2794 0.9906)
			(stroke
				(width 0.1)
				(type default)
			)
			(layer "B.Fab")
		)
		(fp_line
			(start -0.2794 -0.1016)
			(end 0.2794 -0.1016)
			(stroke
				(width 0.1)
				(type default)
			)
			(layer "B.Fab")
		)
		(fp_line
			(start 0.2794 -0.1016)
			(end 0.2794 0.9906)
			(stroke
				(width 0.1)
				(type default)
			)
			(layer "B.Fab")
		)
		(pad "1" smd rect
			(at 0 0 90)
			(size 0.508 0.508)
			(layers "B.Cu" "B.Mask" "B.Paste")
			(net "SVID_ALERT_PVCCIO_CPU0")
		)
		(pad "2" smd rect
			(at 0 0.889 90)
			(size 0.508 0.508)
			(layers "B.Cu" "B.Mask" "B.Paste")
			(net "SVID_ALERT0_CPU0_R_N")
		)
		(zone
			(layer "B.Cu")
			(hatch none 0.5)
			(connect_pads
				(clearance 0)
			)
			(min_thickness 0.25)
			(keepout
				(tracks not_allowed)
				(vias allowed)
				(pads allowed)
				(copperpour not_allowed)
				(footprints allowed)
			)
			(placement
				(enabled no)
				(sheetname "")
			)
			(fill
				(thermal_gap 0.5)
				(thermal_bridge_width 0.5)
				(island_removal_mode 0)
			)
			(polygon
				(pts
					(xy 341.4522 -88.0872) (xy 341.4522 -88.5952) (xy 341.8332 -88.5952) (xy 341.8332 -88.0872)
				)
			)
		)
		(zone
			(layer "B.Cu")
			(hatch none 0.5)
			(connect_pads
				(clearance 0)
			)
			(min_thickness 0.25)
			(keepout
				(tracks allowed)
				(vias not_allowed)
				(pads allowed)
				(copperpour not_allowed)
				(footprints allowed)
			)
			(placement
				(enabled no)
				(sheetname "")
			)
			(fill
				(thermal_gap 0.5)
				(thermal_bridge_width 0.5)
				(island_removal_mode 0)
			)
			(polygon
				(pts
					(xy 341.8332 -88.0872) (xy 341.8332 -88.5952) (xy 341.4522 -88.5952) (xy 341.4522 -88.0872)
				)
			)
		)
	)
)
